# BASEBOARD_FAB2 (Tioga Pass) — schematic parts with pin connectivity, parts 3779–3938 of 4751; source: Cadence DE-HDL packaged netlist (pstxprt.dat, pstxnet.dat, pstchip.dat)

R7P28  RES  150.0 1% CHIP  pkg 0402  page 93 : 1 = PVCCIO_CPU1 ; 2 = H_CPU1_PROCHOT_G_N
R7P29  RES  51.1 1.0% CHIP  pkg 0402  page 112 : 1 = XDP_CPU_TCK0 ; 2 = GND
R7P30  RES  100.0 1% CHIP  pkg 0402  page 112 : 1 = PVCCIO_CPU0 ; 2 = XDP_CPU_MBP0_N
R7R1  RES  51.1 1.0% CHIP  pkg 0402  page 214 : 1 = PVCCIO_CPU1 ; 2 = GND
R7U2  RES  100.0 1% EMPTY  pkg 0402  page 225 : 1 = VSENSE_PVDDQ_GHJ_P ; 2 = VSENSE_PVDDQ_GHJ_N
R7W1  RES  0.0 5% CHIP  pkg 0402  page 118 : 1 = FM_SLPS3_N ; 2 = FM_SLPS3_R_N
R7W2  RES  10.0K 1% EMPTY  pkg 0402  page 166 : 1 = PECI_CPU_G ; 2 = GND
R7W3  RES  10.0K 1% EMPTY  pkg 0402  page 166 : 1 = P3V3_STBY ; 2 = PECI_SEL
R7W4  RES  49.9 1% EMPTY  pkg 0402  page 92 : 1 = PVCCIO_CPU0 ; 2 = P0V7_GTL2104_VREF_0
R7W5  RES  0.0 5% CHIP  pkg 0402  page 153 : 1 = SPI_SWITCH_CS0_N ; 2 = SPI_CS0_PRIMARY_R_N
R7W6  RES  0.0 5% CHIP  pkg 0402  page 118 : 1 = FM_BATTERY_SENSE_EN_N ; 2 = FM_BATTERY_SENSE_EN_R_N
R7W8  RES  0.0 5% CHIP  pkg 0402  page 120 : 1 = FM_POST_CARD_PRES_BMC_N ; 2 = FM_POST_CARD_PRES_BMC_R1_N
R7W9  RES  0.0 5% CHIP  pkg 0402  page 118 : 1 = FM_CPU0_RC_ERROR_N ; 2 = FM_CPU0_RC_ERROR_R_N
R7W10  RES  0.0 5% CHIP  pkg 0402  page 120 : 1 = FM_CPU0_RC_ERROR_N ; 2 = FM_CPU0_RC_ERROR_R1_N
R7W11  RES  0.0 5% CHIP  pkg 0402  page 120 : 1 = FM_CPU1_RC_ERROR_R_N ; 2 = FM_CPU1_RC_ERROR_N
R7W12  RES  0.0 5% CHIP  pkg 0402  page 120 : 1 = FM_CPU1_RC_ERROR_N ; 2 = FM_CPU1_RC_ERROR_R1_N
R7W13  RES  0.0 5% CHIP  pkg 0402  page 119 : 1 = FM_BMC_READY_N ; 2 = FM_BMC_READY_R_N
R7W14  RES  0.0 5% CHIP  pkg 0402  page 120 : 1 = FM_BMC_READY_N ; 2 = FM_BMC_READY_R1_N
R7W15  RES  0.0 5% CHIP  pkg 0402  page 119 : 1 = FM_OCP_MEZZA_PRES ; 2 = FM_OCP_MEZZA_PRES_R
R7W16  RES  0.0 5% CHIP  pkg 0402  page 120 : 1 = IRQ_DIMM_SAVE_LVT3_R_N ; 2 = IRQ_DIMM_SAVE_LVT3_N
R7W17  RES  0.0 5% CHIP  pkg 0402  page 119 : 1 = FM_THROTTLE_R2_N ; 2 = FM_THROTTLE_N
R7W18  RES  0.0 5% CHIP  pkg 0402  page 120 : 1 = IRQ_SML1_PMBUS_ALERT_N ; 2 = IRQ_SML1_PMBUS_ALERT_R1_N
R7W19  RES  4.75K 1% CHIP  pkg 0402  page 118 : 1 = P3V3_STBY ; 2 = FM_BATTERY_SENSE_EN_R_N
R7W20  RES  4.75K 1% CHIP  pkg 0402  page 120 : 1 = P3V3_STBY ; 2 = FM_POST_CARD_PRES_BMC_R1_N
R7W21  RES  4.75K 1% CHIP  pkg 0402  page 118 : 1 = P3V3_STBY ; 2 = RST_BMC_SRST_R_N
R7W22  RES  4.75K 1% CHIP  pkg 0402  page 119 : 1 = P3V3_STBY ; 2 = FM_BMC_ENABLE_N
R8A1  RES  10.0 1% CHIP  pkg 0402  page 235 : 1 = VSENSE_PVNN_PCH_STBY_AVSP ; 2 = VR_PVNN_PCH_AVSP
R8A2  RES  2.67K 1% CHIP  pkg 0402  page 235 : 1 = VR_PVNN_PCH_XADDR2 ; 2 = GND
R8A4  RES  100.0K 1% CHIP  pkg 0402  page 235 : 1 = VR_FET_SW_P12V_STBY_PVDDQ_DEF ; 2 = VR_PVNN_PCH_VINSEN
R8A5  RES  1.00K 1% CHIP  pkg 0402  page 235 : 1 = P3V3_STBY ; 2 = IRQ_PVNN_PCH_VRHOT_N
R8A6  RES  1.00K 1% CHIP  pkg 0402  page 235 : 1 = P3V3_STBY ; 2 = PWRGD_PVNN_PCH_R
R8A7  RES  100.0K 1% EMPTY  pkg 0402  page 235 : 1 = P3V3_STBY ; 2 = VR_PVNN_PCH_VREN
R8A10  RES  5.11K 1% CHIP  pkg 0402  page 237 : 1 = P3V3_STBY ; 2 = PWRGD_P1V8_PCH_STBY_R
R8A11  RES  22.1 1.0% CHIP  pkg 0402  page 237 : 1 = PWRGD_P1V8_PCH_STBY_R ; 2 = PWRGD_P1V8_PCH_STBY
R8A12  RES  475.0 1% CHIP  pkg 0603  page 237 : 1 = P1V8_PCH_STBY ; 2 = GND
R8A13  RES  150.0 1% CHIP  pkg 0402  page 112 : 1 = P1V05_PCH_STBY ; 2 = XDP_TDI
R8A14  RES  150.0 1% CHIP  pkg 0402  page 112 : 1 = P1V05_PCH_STBY ; 2 = XDP_TMS
R8B1  RES  51.1 1.0% CHIP  pkg 0402  page 112 : 1 = XDP_PCH_TCK1 ; 2 = GND
R8B2  RES  1.00K 1% CHIP  pkg 0402  page 112 : 1 = XDP_TRST_N ; 2 = GND
R8B3  RES  4.75K 1% CHIP  pkg 0402  page 91 : 1 = PVPP_ABC ; 2 = FM_MODPRST_HFI0_CPU0_LVT2_N
R8B4  RES  100.0K 1% CHIP  pkg 0402  page 198 : 1 = FM_CTNR_PS_ON ; 2 = GND
R8B5  RES  4.75K 1% CHIP  pkg 0402  page 91 : 1 = PVPP_ABC ; 2 = LED_HFI0_CPU0_N
R8B6  RES  1.8K 1% CHIP  pkg 0402  page 91 : 1 = PVPP_ABC ; 2 = SMB_HFI0_CPU0_LVC2_SCL
R8B7  RES  1.8K 1% CHIP  pkg 0402  page 91 : 1 = PVPP_ABC ; 2 = SMB_HFI0_CPU0_LVC2_SDA
R8B8  RES  4.75K 1% CHIP  pkg 0402  page 91 : 1 = PVPP_ABC ; 2 = RST_HFI0_CPU0_LVT2_N
R8B9  RES  113 1% CHIP  pkg 0402  page 115 : 1 = A_USB2_COMP ; 2 = GND
R8B10  RES  4.75K 1% CHIP  pkg 0402  page 91 : 1 = PVPP_ABC ; 2 = IRQ_HFI0_CPU0_LVT2_N
R8B11  RES  1.8K 1% CHIP  pkg 0402  page 91 : 1 = PVPP_ABC ; 2 = SMB_HFI1_CPU0_LVC2_SCL
R8B12  RES  0.0 5% CHIP  pkg 0402  page 236 : 1 = VSENSE_P1V05_PCH_STBY_AVSN ; 2 = GND
R8B13  RES  1.8K 1% CHIP  pkg 0402  page 91 : 1 = PVPP_ABC ; 2 = SMB_HFI1_CPU0_LVC2_SDA
R8B14  RES  0.0 5% CHIP  pkg 0402  page 236 : 1 = VSENSE_P1V05_PCH_STBY_AVSP ; 2 = P1V05_PCH_STBY
R8B15  RES  100.0 1% EMPTY  pkg 0402  page 236 : 1 = VSENSE_P1V05_PCH_STBY_AVSP ; 2 = VSENSE_P1V05_PCH_STBY_AVSN
R8B16  RES  4.75K 1% CHIP  pkg 0402  page 91 : 1 = PVPP_ABC ; 2 = RST_HFI1_CPU0_LVT2_N
R8B17  RES  4.75K 1% CHIP  pkg 0402  page 91 : 1 = PVPP_ABC ; 2 = IRQ_HFI1_CPU0_LVT2_N
R8B18  RES  4.75K 1% CHIP  pkg 0402  page 91 : 1 = PVPP_ABC ; 2 = LED_HFI1_CPU0_N
R8B19  RES  4.75K 1% CHIP  pkg 0402  page 91 : 1 = PVPP_ABC ; 2 = FM_MODPRST_HFI1_CPU0_LVT2_N
R8B20  RES  10.0 1% CHIP  pkg 0402  page 114 : 1 = H_PMSYNC_CLK_24M_R ; 2 = H_PMSYNC_CLK_24M
R8B21  RES  49.9 1% EMPTY  pkg 0402  page 114 : 1 = H_PMSYNC_CLK_24M ; 2 = GND
R8B23  RES  1.00K 1% CHIP  pkg 0402  page 133 : 1 = P3V3_STBY ; 2 = FM_XRC_PRESENT_N
R8B24  RES  3.3K 5% CHIP  pkg 0402  page 138 : 1 = P3V3_STBY ; 2 = SMB_HOST_STBY_LVC3_SDA_R5
R8B25  RES  4.75K 1% CHIP  pkg 0402  page 151 : 1 = P3V3_STBY ; 2 = FM_BMC_HEARTBEAT_N
R8B26  RES  3.3K 5% CHIP  pkg 0402  page 138 : 1 = P3V3_STBY ; 2 = SMB_HOST_STBY_LVC3_SCL_R5
R8B29  RES  49.9 1% CHIP  pkg 0402  page 178 : 1 = SGPIO_PCH_SSATA_DOUT0 ; 2 = SGPIO_PCH_SSATA_DOUT0_R
R8B30  RES  1.00K 1% CHIP  pkg 0402  page 133 : 1 = P3V3_STBY ; 2 = FM_XRC_READY_N
R8B31  RES  4.75K 1% CHIP  pkg 0402  page 133 : 1 = P3V3_STBY ; 2 = FM_THROTTLE_N
R8B32  RES  10.0K 1% CHIP  pkg 0402  page 115 : 1 = A_USB2_VBUS ; 2 = GND
R8C1  RES  4.75K 1% CHIP  pkg 0402  page 133 : 1 = P3V3_STBY ; 2 = FM_SLT_CFG1
R8C2  RES  4.75K 1% CHIP  pkg 0402  page 133 : 1 = P3V3_STBY ; 2 = IRQ_BMC_PCH_SCI_LPC_N
R8C4  RES  1.00K 1% CHIP  pkg 0402  page 133 : 1 = P3V3_STBY ; 2 = IRQ_BMC_PCH_SMI_LPC_N
R8C6  RES  4.75K 1% CHIP  pkg 0402  page 133 : 1 = P3V3_STBY ; 2 = FM_BIOS_POST_CMPLT_N
R8C7  RES  4.75K 1% CHIP  pkg 0402  page 133 : 1 = P3V3_STBY ; 2 = FM_SLT_CFG0
R8C9  RES  4.75K 1% CHIP  pkg 0402  page 126 : 1 = P3V3_STBY ; 2 = IRQ_SML0_ALERT_N
R8C11  RES  20.0 1% CHIP  pkg 0402  page 138 : 1 = SMB_SMLINK0_STBY_LVC3_SDA_R1 ; 2 = SMB_SMLINK0_STBY_LVC3_SDA
R8C12  RES  20.0 1% CHIP  pkg 0402  page 138 : 1 = SMB_SMLINK0_STBY_LVC3_SCL_R1 ; 2 = SMB_SMLINK0_STBY_LVC3_SCL
R8C14  RES  20.0 1% CHIP  pkg 0402  page 138 : 1 = SMB_HOST_STBY_LVC3_SCL_R1 ; 2 = SMB_HOST_STBY_LVC3_SCL
R8C15  RES  2.0K 1% CHIP  pkg 0402  page 159 : 1 = P3V3_STBY ; 2 = SMB_HOST_STBY_LVC3_SCL_R
R8C16  RES  2.0K 1% CHIP  pkg 0402  page 159 : 1 = P3V3_STBY ; 2 = SMB_HOST_STBY_LVC3_SDA_R
R8C17  RES  1.00K 1% EMPTY  pkg 0402  page 125 : 1 = PU_PCH_TLS_ENABLE_STRAP ; 2 = GND
R8C18  RES  1.00K 1% CHIP  pkg 0402  page 125 : 1 = P3V3_STBY ; 2 = PU_PCH_TLS_ENABLE_STRAP
R8C20  RES  20.0 1% CHIP  pkg 0402  page 138 : 1 = SMB_HOST_STBY_LVC3_SDA_R1 ; 2 = SMB_HOST_STBY_LVC3_SDA
R8C21  RES  100.0 1% CHIP  pkg 0402  page 120 : 1 = A_RCOMP_3P3 ; 2 = GND
R8C23  RES  0.0 5% EMPTY  pkg 0402  page 118 : 1 = FM_GBE_LOM_DISABLE_N ; 2 = FM_10GBE_LOM_DISABLE_N
R8C24  RES  0.0 5% CHIP  pkg 0402  page 118 : 1 = FM_GBE_LOM_DISABLE_N ; 2 = FM_1GB_LOM_DISABLE_N
R8C25  RES  4.75K 1% CHIP  pkg 0402  page 133 : 1 = P3V3_STBY ; 2 = IRQ_PCH_NIC_ALERT_N
R8C26  RES  100.0 1% CHIP  pkg 0402  page 121 : 1 = A_1P8_3P3_RCOMP ; 2 = GND
R8D4  RES  20.0 1% CHIP  pkg 0402  page 138 : 1 = SMB_VR_STBY_LVC3_SCL_R1 ; 2 = SMB_VR_STBY_LVC3_SCL
R8D5  RES  1.00K 1% EMPTY  pkg 0402  page 125 : 1 = PU_ADR_TIMER_HOLD_OFF_N ; 2 = GND
R8D7  RES  20.0 1% CHIP  pkg 0402  page 138 : 1 = SMB_VR_STBY_LVC3_SDA_R1 ; 2 = SMB_VR_STBY_LVC3_SDA
R8D11  RES  33.2 1% CHIP  pkg 0402  page 121 : 1 = RMII_PCH_SPRNGVLLE_ARB_OUT ; 2 = RMII_PCH_SPRNGVLLE_ARB_OUT_R
R8D13  RES  10.0K 1% EMPTY  pkg 0402  page 125 : 1 = P3V3_STBY ; 2 = PU_ADR_TIMER_HOLD_OFF_N
R8D14  RES  4.75K 1% CHIP  pkg 0402  page 133 : 1 = P3V3_STBY ; 2 = FP_PWR_ID_LED_N
R8D15  RES  1.37K 1% CHIP  pkg 0402  page 138 : 1 = P3V3_STBY ; 2 = SMB_VR_STBY_LVC3_SCL
R8D16  RES  10.0K 1% CHIP  pkg 0402  page 125 : 1 = P3V3_STBY ; 2 = RMII_PCH_SPRNGVLLE_ARB_OUT
R8D17  RES  1.37K 1% CHIP  pkg 0402  page 138 : 1 = P3V3_STBY ; 2 = SMB_VR_STBY_LVC3_SDA
R8D19  RES  49.9 1% CHIP  pkg 0402  page 178 : 1 = SGPIO_PCH_SATA_DOUT0 ; 2 = SGPIO_PCH_SATA_DOUT0_R
R8D20  RES  49.9 1% CHIP  pkg 0402  page 178 : 1 = SGPIO_PCH_SATA_LOAD ; 2 = SGPIO_PCH_SATA_LOAD_R
R8D21  RES  1.00K 1% CHIP  pkg 0402  page 135 : 1 = P3V3_STBY ; 2 = FM_IE_DISABLE_N
R8D22  RES  33.2 1% CHIP  pkg 0402  page 157 : 1 = RST_BMC_SRST_R2_N ; 2 = FM_TPM_PRES_RST_N
R8D23  RES  20.0 1% CHIP  pkg 0402  page 167 : 1 = SMB_SENSOR_STBY_LVC3_SDA_R2 ; 2 = SMB_SENSOR_STBY_LVC3_SDA
R8D24  RES  20.0 1% CHIP  pkg 0402  page 167 : 1 = SMB_SENSOR_STBY_LVC3_SCL ; 2 = SMB_SENSOR_STBY_LVC3_SCL_R2
R8D25  RES  4.75K 1% CHIP  pkg 0402  page 157 : 1 = P3V3_STBY ; 2 = RST_BMC_SRST_R2_N
R8D26  RES  4.75K 1% CHIP  pkg 0402  page 170 : 1 = P3V3_STBY ; 2 = IRQ_SML1_PMBUS_ALERT_BUF_N
R8D27  RES  1.00K 1% CHIP  pkg 0402  page 167 : 1 = PD_FRU_WP ; 2 = GND
R8D28  RES  1.00K 1% CHIP  pkg 0402  page 167 : 1 = P3V3_STBY ; 2 = PU_AT24C64_A2
R8D29  RES  4.75K 1% CHIP  pkg 0402  page 89 : 1 = P3V3_STBY ; 2 = IRQ_DIMM_SAVE_LVT3
R8D30  RES  10.0K 1% CHIP  pkg 0402  page 89 : 1 = IRQ_DIMM_SAVE_N ; 2 = IRQ_DIMM_SAVE_R_N
R8D31  RES  4.75K 1% CHIP  pkg 0402  page 89 : 1 = P3V3_STBY ; 2 = IRQ_DIMM_SAVE_LVT3_N
R8D35  RES  0.0 5% CHIP  pkg 0402  page 184 : 1 = SPI_PCH_TPM_CS_N ; 2 = SPI_PCH_TPM_CS_R_N
R8D36  RES  33.2 1% CHIP  pkg 0402  page 157 : 1 = RST_BMC_SRST_R2_N ; 2 = RST_BMC_DDR3_BUF_IN_N
R8D37  RES  4.75K 1% CHIP  pkg 0402  page 196 : 1 = A_PG_P5V ; 2 = GND
R8D38  RES  100.0K 1% CHIP  pkg 0402  page 196 : 1 = P12V ; 2 = A_PG_P12V_MAIN
R8D39  RES  49.9K 1% CHIP  pkg 0402  page 196 : 1 = P5V ; 2 = A_PG_P5V
R8D40  RES  20.0K 1% CHIP  pkg 0402  page 196 : 1 = A_PG_P12V_MAIN ; 2 = GND
R8D41  RES  10.0K 1% CHIP  pkg 0402  page 196 : 1 = P3V3_STBY ; 2 = PWRGD_P12V_MAIN_R
R8D42  RES  100.0 1% CHIP  pkg 0402  page 196 : 1 = PWRGD_P12V_MAIN_R ; 2 = PWRGD_P12V_MAIN
R8D43  RES  0.0 5% CHIP  pkg 0402  page 104 : 1 = FM_156M_CPU0_BRD_OSC_EN ; 2 = FM_CPU0_STL_BRD_OSC_EN
R8D44  RES  10.0K 1% CHIP  pkg 0402  page 133 : 1 = P3V3_STBY ; 2 = FM_CPU0_RC_EN
R8E1  RES  0.0 5% CHIP  pkg 0402  page 184 : 1 = IRQ_SPI_TPM_N_R ; 2 = IRQ_PIRQA_SPI_TPM_N
R8E2  RES  1.00K 1% CHIP  pkg 0402  page 111 : 1 = XDP_SPI_PCH_MOSI_BOOT_HALT_N ; 2 = SPI_PCH_MOSI
R8E3  RES  4.75K 1% CHIP  pkg 0402  page 133 : 1 = P3V3_STBY ; 2 = FM_TPM_PRES_N
R8E4  RES  1.00K 1% EMPTY  pkg 0402  page 125 : 1 = SPI_PCH_MOSI ; 2 = GND
R8E5  RES  33.2 1% CHIP  pkg 0402  page 181 : 1 = FM_CTNR_PS_ON_R ; 2 = FM_CTNR_PS_ON
R8E6  RES  1.00K 1% EMPTY  pkg 0402  page 125 : 1 = P3V3_STBY ; 2 = SPI_PCH_MOSI
R8E7  RES  22.1 1.0% CHIP  pkg 0402  page 196 : 1 = PWRGD_P12V_HSC_DLY_R ; 2 = PWRGD_P12V_HSC_DLY
R8E9  RES  33.2 1% CHIP  pkg 0402  page 184 : 1 = SPI_PCH_CLK ; 2 = SPI_PCH_TPM_CLK_R
R8E10  RES  33.2 1% CHIP  pkg 0402  page 184 : 1 = SPI_PCH_MOSI ; 2 = SPI_PCH_TPM_MOSI_R
R8E11  RES  0.0 5% EMPTY  pkg 0402  page 156 : 1 = FM_MEM_THERM_EVENT_LVT3_N ; 2 = FM_ADR_SMI_GPIO_N
R8E12  RES  4.75K 1% EMPTY  pkg 0402  page 198 : 1 = P3V3_STBY ; 2 = FM_CTNR_PS_ON
R8E13  RES  33.2 1% CHIP  pkg 0402  page 184 : 1 = SPI_PCH_MISO ; 2 = SPI_PCH_TPM_MISO_R
R8E14  RES  4.75K 1% CHIP  pkg 0402  page 136 : 1 = P3V3_STBY ; 2 = RST_PLTRST_TOP_SWAP
R8E16  RES  20.0K 1% CHIP  pkg 0402  page 136 : 1 = FM_BIOS_TOP_SWAP ; 2 = GND
R8E17  RES  33.2 1% CHIP  pkg 0402  page 142 : 1 = IRQ_LVC3_WAKE_R_N ; 2 = IRQ_LVC3_WAKE_N
R8E18  RES  1.0K 0.1% CHIP  pkg 0402  page 241 : 1 = P5V_STBY ; 2 = GND
R8E19  RES  4.75K 1% EMPTY  pkg 0402  page 157 : 1 = P3V3_STBY ; 2 = FM_BIOS_TOP_SWAP
R8E20  RES  33.2 1% CHIP  pkg 0402  page 136 : 1 = FM_BIOS_TOP_SWAP_SPKR_R ; 2 = FM_BIOS_TOP_SWAP_SPKR
R8E21  RES  0.0 5% CHIP  pkg 0402  page 142 : 1 = FM_PE_SPRV_WAKE_N ; 2 = FM_ALL_WAKE_N
R8E22  RES  4.75K 1% CHIP  pkg 0402  page 156 : 1 = P3V3_STBY ; 2 = IRQ_BMC_PCH_NMI_STBY_N
R8E23  RES  4.75K 1% CHIP  pkg 0402  page 142 : 1 = PU_TRI_STATE_EN ; 2 = P3V3_STBY
R8E24  RES  33.2 1% CHIP  pkg 0402  page 156 : 1 = IRQ_BMC_PCH_NMI_STBY_N ; 2 = IRQ_BMC_PCH_NMI_STBY_R_N
R8E25  RES  0.0 5% CHIP  pkg 0402  page 240 : 1 = P3V3_STBY ; 2 = VSENSE_P3V3_STBY
R8E26  RES  0.0 5% CHIP  pkg 0402  page 142 : 1 = FM_PE_OCP_WAKE_N ; 2 = FM_ALL_WAKE_N
R8E27  RES  0.0 5% CHIP  pkg 0402  page 142 : 1 = FM_PE_M2_WAKE_N ; 2 = FM_ALL_WAKE_N
R8E28  RES  0.0 5% CHIP  pkg 0402  page 142 : 1 = FM_PE_SLOTX24_WAKE_N ; 2 = FM_ALL_WAKE_N
R8E29  RES  0.0 5% EMPTY  pkg 0402  page 142 : 1 = FM_PE_BMC_WAKE_N ; 2 = FM_ALL_WAKE_N
R8E30  2K15R2F-1-GP  1%  pkg SMD-RG1  page 142 : 1 = P3V3_STBY ; 2 = FM_ALL_WAKE_N
R8E31  RES  23.2K 1% CHIP  pkg 0402  page 240 : 1 = VSENSE_P3V3_STBY ; 2 = VSENSE_VOUT_P3V3_STBY
R8E32  RES  4.75K 1% CHIP  pkg 0402  page 157 : 1 = P3V3_STBY ; 2 = FP_NMI_BTN_OUT_R_N
R8E33  RES  0.0 5% CHIP  pkg 0402  page 241 : 1 = PWRGD_P12V_HSC_DLY ; 2 = VR_P5V_STBY_EN
R8E34  RES  10.0K 1% CHIP  pkg 0402  page 240 : 1 = VSENSE_VOUT_P3V3_STBY ; 2 = AGND_P3V3_STBY
R8E35  RES  0.0 5% CHIP  pkg 0402  page 240 : 1 = VR_P3V3_STBY_BOOT ; 2 = VR_P3V3_STBY_BOOT_R
R8E36  2K15R2F-1-GP  1%  pkg SMD-RG1  page 142 : 1 = P3V3_STBY ; 2 = FM_PE_SLOTX24_WAKE_N
R8E37  RES  0.0 5% CHIP  pkg 0402  page 241 : 1 = VR_P5V_STBY_VSENSE_R ; 2 = P5V_STBY
R8E38  RES  0.0 5% CHIP  pkg 0402  page 240 : 1 = VSENSE_RGND_P3V3_STBY ; 2 = AGND_P3V3_STBY
R8E39  RES  24.9K 1% CHIP  pkg 0402  page 241 : 1 = VR_P5V_STBY_COMP ; 2 = VR_P5V_STBY_RC_COMP
R8E40  RES  100.0K 1% EMPTY  pkg 0402  page 240 : 1 = P3V3_STBY ; 2 = VR_P3V3_STBY_EN
R8F1  RES  10.0K 1% EMPTY  pkg 0402  page 240 : 1 = PWRGD_P5V_STBY ; 2 = GND
R8F2  RES  0.0 5% CHIP  pkg 0402  page 240 : 1 = PWRGD_P5V_STBY ; 2 = VR_P3V3_STBY_EN
R8F3  RES  2.2 5% EMPTY  pkg 0402  page 240 : 1 = VR_P3V3_STBY_SNUB ; 2 = GND
R8F5  RES  1.00K 1% CHIP  pkg 0402  page 240 : 1 = P3V3_STBY ; 2 = PWRGD_P3V3_STBY_R
R8F6  RES  0.0 5% CHIP  pkg 0402  page 154 : 1 = SPI_PCH_MISO ; 2 = SPI_PCH_MISO_R
